# BASEBOARD_FAB2 (Tioga Pass) — schematic netlist excerpt (pin names and nets, part order shuffled) for the footprints in the layout excerpt that follows; sources: Cadence DE-HDL packaged netlist, KiCad conversion of Wiwynn_Tioga_Pass_MB.brd

C9G18  CAP  47.0PF 50V 5% COG  pkg 0402LF  page 169 : A = A_PVNN_STBY_PCH_SENSOR ; B = GND
R2M5  RES  4.75K 1% CHIP  pkg 0402  page 157 : A = P3V3_STBY ; B = FM_BMC_CPLD_GPO
R6B4  RES  0.0 5% CHIP  pkg 0402  page 21 : A = SVID_DIO1_CPU0 ; B = SVID_DIO1_CPU0_R

(kicad_pcb
	(version 20260206)
	(generator "pcbnew")
	(generator_version "10.0")
	(general
		(thickness 1.6)
		(legacy_teardrops no)
	)
	(paper "A4")
	(title_block
		(title "Wiwynn_Tioga_Pass_MB.brd")
		(comment 1 "Tioga Pass / footprints 1935-1937 of 4770")
	)
	(layers
		(0 "F.Cu" signal "TOP")
		(4 "In1.Cu" signal "L2GND")
		(6 "In2.Cu" signal "L3")
		(8 "In3.Cu" signal "L4GND")
		(10 "In4.Cu" signal "L5")
		(12 "In5.Cu" signal "L6GND")
		(14 "In6.Cu" signal "L7VCC")
		(16 "In7.Cu" signal "L8VCC")
		(18 "In8.Cu" signal "L9GND")
		(20 "In9.Cu" signal "L10")
		(22 "In10.Cu" signal "L11GND")
		(24 "In11.Cu" signal "L12")
		(26 "In12.Cu" signal "L13GND")
		(2 "B.Cu" signal "BOTTOM")
		(9 "F.Adhes" user "F.Adhesive")
		(11 "B.Adhes" user "B.Adhesive")
		(13 "F.Paste" user "Package Geometry/Pastemask Top")
		(15 "B.Paste" user "Package Geometry/Pastemask Bottom")
		(5 "F.SilkS" user "Ref Des/Silkscreen Top")
		(7 "B.SilkS" user "Ref Des/Silkscreen Bottom")
		(1 "F.Mask" user "Board Geometry/Soldermask Top")
		(3 "B.Mask" user "Board Geometry/Soldermask Bottom")
		(17 "Dwgs.User" user "User.Drawings")
		(19 "Cmts.User" user "User.Comments")
		(21 "Eco1.User" user "User.Eco1")
		(23 "Eco2.User" user "User.Eco2")
		(25 "Edge.Cuts" user "Board Geometry/Outline")
		(27 "Margin" user)
		(31 "F.CrtYd" user "Package Geometry/Place Bound Top")
		(29 "B.CrtYd" user "Package Geometry/Place Bound Bottom")
		(35 "F.Fab" user "Ref Des/Assembly Top")
		(33 "B.Fab" user "Ref Des/Assembly Bottom")
	)
	(footprint ""
		(layer "F.Cu")
		(at 412.496 -18.415 90)
		(property "Reference" "C9G18"
			(at 0 0 90)
			(layer "F.SilkS")
			(hide yes)
			(effects
				(font
					(size 1.27 1.27)
				)
			)
		)
		(property "Value" ""
			(at 0 0 90)
			(layer "F.Fab")
			(effects
				(font
					(size 1.27 1.27)
				)
			)
		)
		(duplicate_pad_numbers_are_jumpers no)
		(fp_poly
			(pts
				(xy 0.3048 -0.1016) (xy 0.3048 0.9906) (xy -0.3048 0.9906) (xy -0.3048 -0.1016)
			)
			(stroke
				(width 0)
				(type default)
			)
			(fill no)
			(layer "F.CrtYd")
		)
		(fp_line
			(start 0.3048 -0.1016)
			(end -0.3048 -0.1016)
			(stroke
				(width 0.1)
				(type default)
			)
			(layer "F.Fab")
		)
		(fp_line
			(start -0.3048 -0.1016)
			(end -0.3048 0.9906)
			(stroke
				(width 0.1)
				(type default)
			)
			(layer "F.Fab")
		)
		(fp_line
			(start 0.3048 0.9906)
			(end 0.3048 -0.1016)
			(stroke
				(width 0.1)
				(type default)
			)
			(layer "F.Fab")
		)
		(fp_line
			(start -0.3048 0.9906)
			(end 0.3048 0.9906)
			(stroke
				(width 0.1)
				(type default)
			)
			(layer "F.Fab")
		)
		(pad "1" smd rect
			(at 0 0 90)
			(size 0.508 0.508)
			(layers "F.Cu" "F.Mask" "F.Paste")
			(net "A_PVNN_STBY_PCH_SENSOR")
		)
		(pad "2" smd rect
			(at 0 0.889 90)
			(size 0.508 0.508)
			(layers "F.Cu" "F.Mask" "F.Paste")
			(net "GND")
		)
		(zone
			(layer "F.Cu")
			(hatch none 0.5)
			(connect_pads
				(clearance 0)
			)
			(min_thickness 0.25)
			(keepout
				(tracks allowed)
				(vias not_allowed)
				(pads allowed)
				(copperpour not_allowed)
				(footprints allowed)
			)
			(placement
				(enabled no)
				(sheetname "")
			)
			(fill
				(thermal_gap 0.5)
				(thermal_bridge_width 0.5)
				(island_removal_mode 0)
			)
			(polygon
				(pts
					(xy 412.75 -18.161) (xy 412.75 -18.669) (xy 413.131 -18.669) (xy 413.131 -18.161)
				)
			)
		)
		(zone
			(layer "F.Cu")
			(hatch none 0.5)
			(connect_pads
				(clearance 0)
			)
			(min_thickness 0.25)
			(keepout
				(tracks not_allowed)
				(vias allowed)
				(pads allowed)
				(copperpour not_allowed)
				(footprints allowed)
			)
			(placement
				(enabled no)
				(sheetname "")
			)
			(fill
				(thermal_gap 0.5)
				(thermal_bridge_width 0.5)
				(island_removal_mode 0)
			)
			(polygon
				(pts
					(xy 413.131 -18.161) (xy 413.131 -18.669) (xy 412.75 -18.669) (xy 412.75 -18.161)
				)
			)
		)
	)
	(footprint ""
		(layer "F.Cu")
		(at 419.0492 -113.9952 180)
		(property "Reference" "R2M5"
			(at 0 0 180)
			(layer "F.SilkS")
			(hide yes)
			(effects
				(font
					(size 1.27 1.27)
				)
			)
		)
		(property "Value" ""
			(at 0 0 180)
			(layer "F.Fab")
			(effects
				(font
					(size 1.27 1.27)
				)
			)
		)
		(duplicate_pad_numbers_are_jumpers no)
		(fp_poly
			(pts
				(xy -0.2794 -0.1016) (xy 0.2794 -0.1016) (xy 0.2794 0.9906) (xy -0.2794 0.9906)
			)
			(stroke
				(width 0)
				(type default)
			)
			(fill no)
			(layer "F.CrtYd")
		)
		(fp_line
			(start 0.2794 0.9906)
			(end 0.2794 -0.1016)
			(stroke
				(width 0.1)
				(type default)
			)
			(layer "F.Fab")
		)
		(fp_line
			(start 0.2794 -0.1016)
			(end -0.2794 -0.1016)
			(stroke
				(width 0.1)
				(type default)
			)
			(layer "F.Fab")
		)
		(fp_line
			(start -0.2794 0.9906)
			(end 0.2794 0.9906)
			(stroke
				(width 0.1)
				(type default)
			)
			(layer "F.Fab")
		)
		(fp_line
			(start -0.2794 -0.1016)
			(end -0.2794 0.9906)
			(stroke
				(width 0.1)
				(type default)
			)
			(layer "F.Fab")
		)
		(pad "1" smd rect
			(at 0 0 180)
			(size 0.508 0.508)
			(layers "F.Cu" "F.Mask" "F.Paste")
			(net "P3V3_STBY")
		)
		(pad "2" smd rect
			(at 0 0.889 180)
			(size 0.508 0.508)
			(layers "F.Cu" "F.Mask" "F.Paste")
			(net "FM_BMC_CPLD_GPO")
		)
		(zone
			(layer "F.Cu")
			(hatch none 0.5)
			(connect_pads
				(clearance 0)
			)
			(min_thickness 0.25)
			(keepout
				(tracks not_allowed)
				(vias allowed)
				(pads allowed)
				(copperpour not_allowed)
				(footprints allowed)
			)
			(placement
				(enabled no)
				(sheetname "")
			)
			(fill
				(thermal_gap 0.5)
				(thermal_bridge_width 0.5)
				(island_removal_mode 0)
			)
			(polygon
				(pts
					(xy 419.3032 -114.6302) (xy 418.7952 -114.6302) (xy 418.7952 -114.2492) (xy 419.3032 -114.2492)
				)
			)
		)
		(zone
			(layer "F.Cu")
			(hatch none 0.5)
			(connect_pads
				(clearance 0)
			)
			(min_thickness 0.25)
			(keepout
				(tracks allowed)
				(vias not_allowed)
				(pads allowed)
				(copperpour not_allowed)
				(footprints allowed)
			)
			(placement
				(enabled no)
				(sheetname "")
			)
			(fill
				(thermal_gap 0.5)
				(thermal_bridge_width 0.5)
				(island_removal_mode 0)
			)
			(polygon
				(pts
					(xy 419.3032 -114.2492) (xy 418.7952 -114.2492) (xy 418.7952 -114.6302) (xy 419.3032 -114.6302)
				)
			)
		)
	)
	(footprint ""
		(layer "F.Cu")
		(at 323.516498 -128.013714 180)
		(property "Reference" "R6B4"
			(at 0 0 180)
			(layer "F.SilkS")
			(hide yes)
			(effects
				(font
					(size 1.27 1.27)
				)
			)
		)
		(property "Value" ""
			(at 0 0 180)
			(layer "F.Fab")
			(effects
				(font
					(size 1.27 1.27)
				)
			)
		)
		(duplicate_pad_numbers_are_jumpers no)
		(fp_poly
			(pts
				(xy -0.2794 -0.1016) (xy 0.2794 -0.1016) (xy 0.2794 0.9906) (xy -0.2794 0.9906)
			)
			(stroke
				(width 0)
				(type default)
			)
			(fill no)
			(layer "F.CrtYd")
		)
		(fp_line
			(start 0.2794 0.9906)
			(end 0.2794 -0.1016)
			(stroke
				(width 0.1)
				(type default)
			)
			(layer "F.Fab")
		)
		(fp_line
			(start 0.2794 -0.1016)
			(end -0.2794 -0.1016)
			(stroke
				(width 0.1)
				(type default)
			)
			(layer "F.Fab")
		)
		(fp_line
			(start -0.2794 0.9906)
			(end 0.2794 0.9906)
			(stroke
				(width 0.1)
				(type default)
			)
			(layer "F.Fab")
		)
		(fp_line
			(start -0.2794 -0.1016)
			(end -0.2794 0.9906)
			(stroke
				(width 0.1)
				(type default)
			)
			(layer "F.Fab")
		)
		(pad "1" smd rect
			(at 0 0 180)
			(size 0.508 0.508)
			(layers "F.Cu" "F.Mask" "F.Paste")
			(net "SVID_DIO1_CPU0")
		)
		(pad "2" smd rect
			(at 0 0.889 180)
			(size 0.508 0.508)
			(layers "F.Cu" "F.Mask" "F.Paste")
			(net "SVID_DIO1_CPU0_R")
		)
		(zone
			(layer "F.Cu")
			(hatch none 0.5)
			(connect_pads
				(clearance 0)
			)
			(min_thickness 0.25)
			(keepout
				(tracks not_allowed)
				(vias allowed)
				(pads allowed)
				(copperpour not_allowed)
				(footprints allowed)
			)
			(placement
				(enabled no)
				(sheetname "")
			)
			(fill
				(thermal_gap 0.5)
				(thermal_bridge_width 0.5)
				(island_removal_mode 0)
			)
			(polygon
				(pts
					(xy 323.770498 -128.648714) (xy 323.262498 -128.648714) (xy 323.262498 -128.267714) (xy 323.770498 -128.267714)
				)
			)
		)
		(zone
			(layer "F.Cu")
			(hatch none 0.5)
			(connect_pads
				(clearance 0)
			)
			(min_thickness 0.25)
			(keepout
				(tracks allowed)
				(vias not_allowed)
				(pads allowed)
				(copperpour not_allowed)
				(footprints allowed)
			)
			(placement
				(enabled no)
				(sheetname "")
			)
			(fill
				(thermal_gap 0.5)
				(thermal_bridge_width 0.5)
				(island_removal_mode 0)
			)
			(polygon
				(pts
					(xy 323.770498 -128.267714) (xy 323.262498 -128.267714) (xy 323.262498 -128.648714) (xy 323.770498 -128.648714)
				)
			)
		)
	)
)
